(kicad_pcb
	(version 20260206)
	(generator "pcbnew")
	(generator_version "10.0")
	(general
		(thickness 1.6)
		(legacy_teardrops no)
	)
	(paper "A4")
	(title_block
		(title "01162023_DA0F0TEBIF0_F0T_Expander_BD_F_brd_V02_OCP.brd")
		(comment 1 "Grand Teton / footprints 3737-3743 of 9728")
	)
	(layers
		(0 "F.Cu" signal "TOP")
		(4 "In1.Cu" signal "GND")
		(6 "In2.Cu" signal "VCC")
		(8 "In3.Cu" signal "VCC1")
		(10 "In4.Cu" signal "GND1")
		(12 "In5.Cu" signal "IN1")
		(14 "In6.Cu" signal "GND2")
		(16 "In7.Cu" signal "IN2")
		(18 "In8.Cu" signal "GND3")
		(20 "In9.Cu" signal "IN3")
		(22 "In10.Cu" signal "GND4")
		(24 "In11.Cu" signal "IN4")
		(26 "In12.Cu" signal "GND5")
		(28 "In13.Cu" signal "IN5")
		(30 "In14.Cu" signal "GND6")
		(32 "In15.Cu" signal "IN6")
		(34 "In16.Cu" signal "GND7")
		(2 "B.Cu" signal "BOTTOM")
		(9 "F.Adhes" user "F.Adhesive")
		(11 "B.Adhes" user "B.Adhesive")
		(13 "F.Paste" user "Package Geometry/Pastemask Top")
		(15 "B.Paste" user "Package Geometry/Pastemask Bottom")
		(5 "F.SilkS" user "Ref Des/Silkscreen Top")
		(7 "B.SilkS" user "Ref Des/Silkscreen Bottom")
		(1 "F.Mask" user "Board Geometry/Soldermask Top")
		(3 "B.Mask" user "Board Geometry/Soldermask Bottom")
		(17 "Dwgs.User" user "User.Drawings")
		(19 "Cmts.User" user "User.Comments")
		(21 "Eco1.User" user "User.Eco1")
		(23 "Eco2.User" user "User.Eco2")
		(25 "Edge.Cuts" user "Board Geometry/Outline")
		(27 "Margin" user)
		(31 "F.CrtYd" user "Package Geometry/Place Bound Top")
		(29 "B.CrtYd" user "Package Geometry/Place Bound Bottom")
		(35 "F.Fab" user "Ref Des/Assembly Top")
		(33 "B.Fab" user "Ref Des/Assembly Bottom")
	)
	(footprint ""
		(layer "F.Cu")
		(at 59.10326 -59.571636 90)
		(property "Reference" "PR265"
			(at 0 0 90)
			(layer "F.SilkS")
			(hide yes)
			(effects
				(font
					(size 1.27 1.27)
				)
			)
		)
		(property "Value" ""
			(at 0 0 90)
			(layer "F.Fab")
			(effects
				(font
					(size 1.27 1.27)
				)
			)
		)
		(duplicate_pad_numbers_are_jumpers no)
		(fp_line
			(start 0.7874 -0.4064)
			(end 0.7874 0.4064)
			(stroke
				(width 0.1524)
				(type default)
			)
			(layer "F.SilkS")
		)
		(fp_line
			(start -0.7874 -0.4064)
			(end 0.7874 -0.4064)
			(stroke
				(width 0.1524)
				(type default)
			)
			(layer "F.SilkS")
		)
		(fp_line
			(start 0.7874 0.4064)
			(end -0.7874 0.4064)
			(stroke
				(width 0.1524)
				(type default)
			)
			(layer "F.SilkS")
		)
		(fp_line
			(start -0.7874 0.4064)
			(end -0.7874 -0.4064)
			(stroke
				(width 0.1524)
				(type default)
			)
			(layer "F.SilkS")
		)
		(fp_line
			(start -0.12065 -0.305054)
			(end -0.12065 -0.2794)
			(stroke
				(width 0.1)
				(type default)
			)
			(layer "F.Fab")
		)
		(fp_line
			(start -0.67945 -0.305054)
			(end -0.12065 -0.305054)
			(stroke
				(width 0.1)
				(type default)
			)
			(layer "F.Fab")
		)
		(fp_line
			(start 0.67945 -0.3048)
			(end 0.67945 0.3048)
			(stroke
				(width 0.1)
				(type default)
			)
			(layer "F.Fab")
		)
		(fp_line
			(start 0.12065 -0.3048)
			(end 0.67945 -0.3048)
			(stroke
				(width 0.1)
				(type default)
			)
			(layer "F.Fab")
		)
		(fp_line
			(start 0.12065 -0.2794)
			(end 0.12065 -0.3048)
			(stroke
				(width 0.1)
				(type default)
			)
			(layer "F.Fab")
		)
		(fp_line
			(start -0.12065 -0.2794)
			(end 0.12065 -0.2794)
			(stroke
				(width 0.1)
				(type default)
			)
			(layer "F.Fab")
		)
		(fp_line
			(start 0.120396 0.2794)
			(end -0.12065 0.2794)
			(stroke
				(width 0.1)
				(type default)
			)
			(layer "F.Fab")
		)
		(fp_line
			(start -0.12065 0.2794)
			(end -0.12065 0.3048)
			(stroke
				(width 0.1)
				(type default)
			)
			(layer "F.Fab")
		)
		(fp_line
			(start 0.67945 0.3048)
			(end 0.120396 0.3048)
			(stroke
				(width 0.1)
				(type default)
			)
			(layer "F.Fab")
		)
		(fp_line
			(start 0.120396 0.3048)
			(end 0.120396 0.2794)
			(stroke
				(width 0.1)
				(type default)
			)
			(layer "F.Fab")
		)
		(fp_line
			(start -0.12065 0.3048)
			(end -0.67945 0.3048)
			(stroke
				(width 0.1)
				(type default)
			)
			(layer "F.Fab")
		)
		(fp_line
			(start -0.67945 0.3048)
			(end -0.67945 -0.305054)
			(stroke
				(width 0.1)
				(type default)
			)
			(layer "F.Fab")
		)
		(pad "1" smd circle
			(at -0.40005 0 90)
			(size 0 0)
			(layers "F.Cu" "F.Mask" "F.Paste")
			(net "P3V3_SSD2_OCP")
		)
		(pad "2" smd circle
			(at 0.40005 0 90)
			(size 0 0)
			(layers "F.Cu" "F.Mask" "F.Paste")
			(net "GND")
		)
	)
	(footprint ""
		(layer "F.Cu")
		(at 254.521208 -355.742748 -90)
		(property "Reference" "PC6606"
			(at 0 0 270)
			(layer "F.SilkS")
			(hide yes)
			(effects
				(font
					(size 1.27 1.27)
				)
			)
		)
		(property "Value" ""
			(at 0 0 270)
			(layer "F.Fab")
			(effects
				(font
					(size 1.27 1.27)
				)
			)
		)
		(duplicate_pad_numbers_are_jumpers no)
		(fp_line
			(start -1.2954 0.5842)
			(end -1.2954 -0.5842)
			(stroke
				(width 0.1524)
				(type default)
			)
			(layer "F.SilkS")
		)
		(fp_line
			(start 1.2954 0.5842)
			(end -1.2954 0.5842)
			(stroke
				(width 0.1524)
				(type default)
			)
			(layer "F.SilkS")
		)
		(fp_line
			(start -1.2954 -0.5842)
			(end 1.2954 -0.5842)
			(stroke
				(width 0.1524)
				(type default)
			)
			(layer "F.SilkS")
		)
		(fp_line
			(start 1.2954 -0.5842)
			(end 1.2954 0.5842)
			(stroke
				(width 0.1524)
				(type default)
			)
			(layer "F.SilkS")
		)
		(fp_line
			(start -0.8636 0.4572)
			(end -0.8636 0.4064)
			(stroke
				(width 0.1)
				(type default)
			)
			(layer "F.Fab")
		)
		(fp_line
			(start 0.8636 0.4572)
			(end -0.8636 0.4572)
			(stroke
				(width 0.1)
				(type default)
			)
			(layer "F.Fab")
		)
		(fp_line
			(start -1.1938 0.4064)
			(end -1.1938 -0.4064)
			(stroke
				(width 0.1)
				(type default)
			)
			(layer "F.Fab")
		)
		(fp_line
			(start -0.8636 0.4064)
			(end -1.1938 0.4064)
			(stroke
				(width 0.1)
				(type default)
			)
			(layer "F.Fab")
		)
		(fp_line
			(start 0.8636 0.4064)
			(end 0.8636 0.4572)
			(stroke
				(width 0.1)
				(type default)
			)
			(layer "F.Fab")
		)
		(fp_line
			(start 1.1938 0.4064)
			(end 0.8636 0.4064)
			(stroke
				(width 0.1)
				(type default)
			)
			(layer "F.Fab")
		)
		(fp_line
			(start -1.1938 -0.4064)
			(end -0.8636 -0.4064)
			(stroke
				(width 0.1)
				(type default)
			)
			(layer "F.Fab")
		)
		(fp_line
			(start -0.8636 -0.4064)
			(end -0.8636 -0.4572)
			(stroke
				(width 0.1)
				(type default)
			)
			(layer "F.Fab")
		)
		(fp_line
			(start 0.8636 -0.4064)
			(end 1.1938 -0.4064)
			(stroke
				(width 0.1)
				(type default)
			)
			(layer "F.Fab")
		)
		(fp_line
			(start 1.1938 -0.4064)
			(end 1.1938 0.4064)
			(stroke
				(width 0.1)
				(type default)
			)
			(layer "F.Fab")
		)
		(fp_line
			(start -0.8636 -0.4572)
			(end 0.8636 -0.4572)
			(stroke
				(width 0.1)
				(type default)
			)
			(layer "F.Fab")
		)
		(fp_line
			(start 0.8636 -0.4572)
			(end 0.8636 -0.4064)
			(stroke
				(width 0.1)
				(type default)
			)
			(layer "F.Fab")
		)
		(pad "1" smd rect
			(at -0.7366 0 180)
			(size 0.7112 0.8128)
			(layers "F.Cu" "F.Mask" "F.Paste")
			(net "P12V_AUX")
		)
		(pad "2" smd rect
			(at 0.7366 0 180)
			(size 0.7112 0.8128)
			(layers "F.Cu" "F.Mask" "F.Paste")
			(net "GND")
		)
	)
	(footprint ""
		(layer "F.Cu")
		(at 407.693114 -392.016742)
		(property "Reference" "R6775"
			(at 0 0 0)
			(layer "F.SilkS")
			(hide yes)
			(effects
				(font
					(size 1.27 1.27)
				)
			)
		)
		(property "Value" ""
			(at 0 0 0)
			(layer "F.Fab")
			(effects
				(font
					(size 1.27 1.27)
				)
			)
		)
		(duplicate_pad_numbers_are_jumpers no)
		(fp_line
			(start -0.7874 -0.4064)
			(end 0.7874 -0.4064)
			(stroke
				(width 0.1524)
				(type default)
			)
			(layer "F.SilkS")
		)
		(fp_line
			(start -0.7874 0.4064)
			(end -0.7874 -0.4064)
			(stroke
				(width 0.1524)
				(type default)
			)
			(layer "F.SilkS")
		)
		(fp_line
			(start 0.7874 -0.4064)
			(end 0.7874 0.4064)
			(stroke
				(width 0.1524)
				(type default)
			)
			(layer "F.SilkS")
		)
		(fp_line
			(start 0.7874 0.4064)
			(end -0.7874 0.4064)
			(stroke
				(width 0.1524)
				(type default)
			)
			(layer "F.SilkS")
		)
		(fp_line
			(start -0.67945 -0.305054)
			(end -0.12065 -0.305054)
			(stroke
				(width 0.1)
				(type default)
			)
			(layer "F.Fab")
		)
		(fp_line
			(start -0.67945 0.3048)
			(end -0.67945 -0.305054)
			(stroke
				(width 0.1)
				(type default)
			)
			(layer "F.Fab")
		)
		(fp_line
			(start -0.12065 -0.305054)
			(end -0.12065 -0.2794)
			(stroke
				(width 0.1)
				(type default)
			)
			(layer "F.Fab")
		)
		(fp_line
			(start -0.12065 -0.2794)
			(end 0.12065 -0.2794)
			(stroke
				(width 0.1)
				(type default)
			)
			(layer "F.Fab")
		)
		(fp_line
			(start -0.12065 0.2794)
			(end -0.12065 0.3048)
			(stroke
				(width 0.1)
				(type default)
			)
			(layer "F.Fab")
		)
		(fp_line
			(start -0.12065 0.3048)
			(end -0.67945 0.3048)
			(stroke
				(width 0.1)
				(type default)
			)
			(layer "F.Fab")
		)
		(fp_line
			(start 0.120396 0.2794)
			(end -0.12065 0.2794)
			(stroke
				(width 0.1)
				(type default)
			)
			(layer "F.Fab")
		)
		(fp_line
			(start 0.120396 0.3048)
			(end 0.120396 0.2794)
			(stroke
				(width 0.1)
				(type default)
			)
			(layer "F.Fab")
		)
		(fp_line
			(start 0.12065 -0.3048)
			(end 0.67945 -0.3048)
			(stroke
				(width 0.1)
				(type default)
			)
			(layer "F.Fab")
		)
		(fp_line
			(start 0.12065 -0.2794)
			(end 0.12065 -0.3048)
			(stroke
				(width 0.1)
				(type default)
			)
			(layer "F.Fab")
		)
		(fp_line
			(start 0.67945 -0.3048)
			(end 0.67945 0.3048)
			(stroke
				(width 0.1)
				(type default)
			)
			(layer "F.Fab")
		)
		(fp_line
			(start 0.67945 0.3048)
			(end 0.120396 0.3048)
			(stroke
				(width 0.1)
				(type default)
			)
			(layer "F.Fab")
		)
		(pad "1" smd circle
			(at -0.40005 0)
			(size 0 0)
			(layers "F.Cu" "F.Mask" "F.Paste")
			(net "PRSNT_GPU_A1_R_N")
		)
		(pad "2" smd circle
			(at 0.40005 0)
			(size 0 0)
			(layers "F.Cu" "F.Mask" "F.Paste")
			(net "PRSNT_GPU_A1_N")
		)
	)
	(footprint ""
		(layer "F.Cu")
		(at 82.661506 -124.991114 180)
		(property "Reference" "C25"
			(at 0 0 180)
			(layer "F.SilkS")
			(hide yes)
			(effects
				(font
					(size 1.27 1.27)
				)
			)
		)
		(property "Value" ""
			(at 0 0 180)
			(layer "F.Fab")
			(effects
				(font
					(size 1.27 1.27)
				)
			)
		)
		(duplicate_pad_numbers_are_jumpers no)
		(fp_line
			(start 0.299974 0.150114)
			(end -0.299974 0.150114)
			(stroke
				(width 0.1)
				(type default)
			)
			(layer "F.Fab")
		)
		(fp_line
			(start 0.299974 -0.150114)
			(end 0.299974 0.150114)
			(stroke
				(width 0.1)
				(type default)
			)
			(layer "F.Fab")
		)
		(fp_line
			(start -0.299974 0.150114)
			(end -0.299974 -0.150114)
			(stroke
				(width 0.1)
				(type default)
			)
			(layer "F.Fab")
		)
		(fp_line
			(start -0.299974 -0.150114)
			(end 0.299974 -0.150114)
			(stroke
				(width 0.1)
				(type default)
			)
			(layer "F.Fab")
		)
		(pad "1" smd rect
			(at -0.2667 0 180)
			(size 0.3048 0.381)
			(layers "F.Cu" "F.Mask" "F.Paste")
			(net "P5E_PEX0_STN0_TX_DP<3>")
		)
		(pad "2" smd rect
			(at 0.2667 0 180)
			(size 0.3048 0.381)
			(layers "F.Cu" "F.Mask" "F.Paste")
			(net "P5E_PEX0_STN0_TX_C_DP<3>")
		)
	)
	(footprint ""
		(layer "F.Cu")
		(at 303.99609 -47.20082 90)
		(property "Reference" "C328"
			(at 0 0 90)
			(layer "F.SilkS")
			(hide yes)
			(effects
				(font
					(size 1.27 1.27)
				)
			)
		)
		(property "Value" ""
			(at 0 0 90)
			(layer "F.Fab")
			(effects
				(font
					(size 1.27 1.27)
				)
			)
		)
		(duplicate_pad_numbers_are_jumpers no)
		(fp_line
			(start 0.7874 -0.4064)
			(end 0.7874 0.4064)
			(stroke
				(width 0.1524)
				(type default)
			)
			(layer "F.SilkS")
		)
		(fp_line
			(start -0.7874 -0.4064)
			(end 0.7874 -0.4064)
			(stroke
				(width 0.1524)
				(type default)
			)
			(layer "F.SilkS")
		)
		(fp_line
			(start 0.7874 0.4064)
			(end -0.7874 0.4064)
			(stroke
				(width 0.1524)
				(type default)
			)
			(layer "F.SilkS")
		)
		(fp_line
			(start -0.7874 0.4064)
			(end -0.7874 -0.4064)
			(stroke
				(width 0.1524)
				(type default)
			)
			(layer "F.SilkS")
		)
		(fp_line
			(start -0.12065 -0.305054)
			(end -0.12065 -0.2794)
			(stroke
				(width 0.1)
				(type default)
			)
			(layer "F.Fab")
		)
		(fp_line
			(start -0.67945 -0.305054)
			(end -0.12065 -0.305054)
			(stroke
				(width 0.1)
				(type default)
			)
			(layer "F.Fab")
		)
		(fp_line
			(start 0.67945 -0.3048)
			(end 0.67945 0.3048)
			(stroke
				(width 0.1)
				(type default)
			)
			(layer "F.Fab")
		)
		(fp_line
			(start 0.12065 -0.3048)
			(end 0.67945 -0.3048)
			(stroke
				(width 0.1)
				(type default)
			)
			(layer "F.Fab")
		)
		(fp_line
			(start 0.12065 -0.2794)
			(end 0.12065 -0.3048)
			(stroke
				(width 0.1)
				(type default)
			)
			(layer "F.Fab")
		)
		(fp_line
			(start -0.12065 -0.2794)
			(end 0.12065 -0.2794)
			(stroke
				(width 0.1)
				(type default)
			)
			(layer "F.Fab")
		)
		(fp_line
			(start 0.120396 0.2794)
			(end -0.12065 0.2794)
			(stroke
				(width 0.1)
				(type default)
			)
			(layer "F.Fab")
		)
		(fp_line
			(start -0.12065 0.2794)
			(end -0.12065 0.3048)
			(stroke
				(width 0.1)
				(type default)
			)
			(layer "F.Fab")
		)
		(fp_line
			(start 0.67945 0.3048)
			(end 0.120396 0.3048)
			(stroke
				(width 0.1)
				(type default)
			)
			(layer "F.Fab")
		)
		(fp_line
			(start 0.120396 0.3048)
			(end 0.120396 0.2794)
			(stroke
				(width 0.1)
				(type default)
			)
			(layer "F.Fab")
		)
		(fp_line
			(start -0.12065 0.3048)
			(end -0.67945 0.3048)
			(stroke
				(width 0.1)
				(type default)
			)
			(layer "F.Fab")
		)
		(fp_line
			(start -0.67945 0.3048)
			(end -0.67945 -0.305054)
			(stroke
				(width 0.1)
				(type default)
			)
			(layer "F.Fab")
		)
		(pad "1" smd circle
			(at -0.40005 0 90)
			(size 0 0)
			(layers "F.Cu" "F.Mask" "F.Paste")
			(net "P12V_SSD10_R")
		)
		(pad "2" smd circle
			(at 0.40005 0 90)
			(size 0 0)
			(layers "F.Cu" "F.Mask" "F.Paste")
			(net "GND")
		)
	)
	(footprint ""
		(layer "F.Cu")
		(at 426.543724 -42.84091)
		(property "Reference" "R659"
			(at 0 0 0)
			(layer "F.SilkS")
			(hide yes)
			(effects
				(font
					(size 1.27 1.27)
				)
			)
		)
		(property "Value" ""
			(at 0 0 0)
			(layer "F.Fab")
			(effects
				(font
					(size 1.27 1.27)
				)
			)
		)
		(duplicate_pad_numbers_are_jumpers no)
		(fp_line
			(start -0.7874 -0.4064)
			(end 0.7874 -0.4064)
			(stroke
				(width 0.1524)
				(type default)
			)
			(layer "F.SilkS")
		)
		(fp_line
			(start -0.7874 0.4064)
			(end -0.7874 -0.4064)
			(stroke
				(width 0.1524)
				(type default)
			)
			(layer "F.SilkS")
		)
		(fp_line
			(start 0.7874 -0.4064)
			(end 0.7874 0.4064)
			(stroke
				(width 0.1524)
				(type default)
			)
			(layer "F.SilkS")
		)
		(fp_line
			(start 0.7874 0.4064)
			(end -0.7874 0.4064)
			(stroke
				(width 0.1524)
				(type default)
			)
			(layer "F.SilkS")
		)
		(fp_line
			(start -0.67945 -0.305054)
			(end -0.12065 -0.305054)
			(stroke
				(width 0.1)
				(type default)
			)
			(layer "F.Fab")
		)
		(fp_line
			(start -0.67945 0.3048)
			(end -0.67945 -0.305054)
			(stroke
				(width 0.1)
				(type default)
			)
			(layer "F.Fab")
		)
		(fp_line
			(start -0.12065 -0.305054)
			(end -0.12065 -0.2794)
			(stroke
				(width 0.1)
				(type default)
			)
			(layer "F.Fab")
		)
		(fp_line
			(start -0.12065 -0.2794)
			(end 0.12065 -0.2794)
			(stroke
				(width 0.1)
				(type default)
			)
			(layer "F.Fab")
		)
		(fp_line
			(start -0.12065 0.2794)
			(end -0.12065 0.3048)
			(stroke
				(width 0.1)
				(type default)
			)
			(layer "F.Fab")
		)
		(fp_line
			(start -0.12065 0.3048)
			(end -0.67945 0.3048)
			(stroke
				(width 0.1)
				(type default)
			)
			(layer "F.Fab")
		)
		(fp_line
			(start 0.120396 0.2794)
			(end -0.12065 0.2794)
			(stroke
				(width 0.1)
				(type default)
			)
			(layer "F.Fab")
		)
		(fp_line
			(start 0.120396 0.3048)
			(end 0.120396 0.2794)
			(stroke
				(width 0.1)
				(type default)
			)
			(layer "F.Fab")
		)
		(fp_line
			(start 0.12065 -0.3048)
			(end 0.67945 -0.3048)
			(stroke
				(width 0.1)
				(type default)
			)
			(layer "F.Fab")
		)
		(fp_line
			(start 0.12065 -0.2794)
			(end 0.12065 -0.3048)
			(stroke
				(width 0.1)
				(type default)
			)
			(layer "F.Fab")
		)
		(fp_line
			(start 0.67945 -0.3048)
			(end 0.67945 0.3048)
			(stroke
				(width 0.1)
				(type default)
			)
			(layer "F.Fab")
		)
		(fp_line
			(start 0.67945 0.3048)
			(end 0.120396 0.3048)
			(stroke
				(width 0.1)
				(type default)
			)
			(layer "F.Fab")
		)
		(pad "1" smd circle
			(at -0.40005 0)
			(size 0 0)
			(layers "F.Cu" "F.Mask" "F.Paste")
			(net "SSD14_ADC_A1")
		)
		(pad "2" smd circle
			(at 0.40005 0)
			(size 0 0)
			(layers "F.Cu" "F.Mask" "F.Paste")
			(net "P3V3_AUX")
		)
	)
	(footprint ""
		(layer "F.Cu")
		(at 180.814472 -356.244906 90)
		(property "Reference" "C383"
			(at 0 0 90)
			(layer "F.SilkS")
			(hide yes)
			(effects
				(font
					(size 1.27 1.27)
				)
			)
		)
		(property "Value" ""
			(at 0 0 90)
			(layer "F.Fab")
			(effects
				(font
					(size 1.27 1.27)
				)
			)
		)
		(duplicate_pad_numbers_are_jumpers no)
		(fp_line
			(start 0.299974 -0.150114)
			(end 0.299974 0.150114)
			(stroke
				(width 0.1)
				(type default)
			)
			(layer "F.Fab")
		)
		(fp_line
			(start -0.299974 -0.150114)
			(end 0.299974 -0.150114)
			(stroke
				(width 0.1)
				(type default)
			)
			(layer "F.Fab")
		)
		(fp_line
			(start 0.299974 0.150114)
			(end -0.299974 0.150114)
			(stroke
				(width 0.1)
				(type default)
			)
			(layer "F.Fab")
		)
		(fp_line
			(start -0.299974 0.150114)
			(end -0.299974 -0.150114)
			(stroke
				(width 0.1)
				(type default)
			)
			(layer "F.Fab")
		)
		(pad "1" smd rect
			(at -0.2667 0 90)
			(size 0.3048 0.381)
			(layers "F.Cu" "F.Mask" "F.Paste")
			(net "P5E_PEX1_STN7_TX_DN<122>")
		)
		(pad "2" smd rect
			(at 0.2667 0 90)
			(size 0.3048 0.381)
			(layers "F.Cu" "F.Mask" "F.Paste")
			(net "P5E_PEX1_STN7_TX_C_DN<122>")
		)
	)
)
